#ISCELL
  pure_quanta quanta_title_block_c *
  *
#CELL
  pure_quanta q_res *
  page225_i11
#CELL
  pure_quanta q_res *
  page225_i12
#ISCELL
  logical_power universal_power *
  page225_i13
#CELL
  pure_quanta pca9617adp *
  page225_i17
#ISCELL
  standard offpage *
  page225_i18
#ISCELL
  standard offpage *
  page225_i19
#ISCELL
  standard offpage *
  page225_i22
#ISCELL
  standard offpage *
  page225_i23
#CELL
  pure_quanta q_res *
  page225_i24
#CELL
  pure_quanta q_res *
  page225_i25
#CELL
  pure_quanta q_res *
  page225_i26
#CELL
  pure_quanta q_res *
  page225_i27
#ISCELL
  standard offpage *
  page225_i28
#ISCELL
  standard offpage *
  page225_i29
#ISCELL
  logical_power universal_gnd *
  page225_i3
#ISCELL
  standard offpage *
  page225_i30
#ISCELL
  standard offpage *
  page225_i31
#CELL
  pure_quanta q_res *
  page225_i32
#CELL
  pure_quanta q_res *
  page225_i33
#CELL
  pure_quanta q_res *
  page225_i34
#ISCELL
  standard offpage *
  page225_i35
#ISCELL
  standard offpage *
  page225_i36
#ISCELL
  logical_power universal_gnd *
  page225_i4
#CELL
  pure_quanta q_cap *
  page225_i5
#ISCELL
  logical_power universal_power *
  page225_i6
#ISCELL
  logical_power universal_gnd *
  page225_i7
#CELL
  pure_quanta q_cap *
  page225_i8
#ISCELL
  logical_power universal_power *
  page225_i9
